(kicad_pcb
	(version 20260206)
	(generator "pcbnew")
	(generator_version "10.0")
	(general
		(thickness 1.6)
		(legacy_teardrops no)
	)
	(paper "A4")
	(title_block
		(title "Wiwynn_Tioga_Pass_MB.brd")
		(comment 1 "Tioga Pass / footprints 2019-2025 of 4770")
	)
	(layers
		(0 "F.Cu" signal "TOP")
		(4 "In1.Cu" signal "L2GND")
		(6 "In2.Cu" signal "L3")
		(8 "In3.Cu" signal "L4GND")
		(10 "In4.Cu" signal "L5")
		(12 "In5.Cu" signal "L6GND")
		(14 "In6.Cu" signal "L7VCC")
		(16 "In7.Cu" signal "L8VCC")
		(18 "In8.Cu" signal "L9GND")
		(20 "In9.Cu" signal "L10")
		(22 "In10.Cu" signal "L11GND")
		(24 "In11.Cu" signal "L12")
		(26 "In12.Cu" signal "L13GND")
		(2 "B.Cu" signal "BOTTOM")
		(9 "F.Adhes" user "F.Adhesive")
		(11 "B.Adhes" user "B.Adhesive")
		(13 "F.Paste" user "Package Geometry/Pastemask Top")
		(15 "B.Paste" user "Package Geometry/Pastemask Bottom")
		(5 "F.SilkS" user "Ref Des/Silkscreen Top")
		(7 "B.SilkS" user "Ref Des/Silkscreen Bottom")
		(1 "F.Mask" user "Board Geometry/Soldermask Top")
		(3 "B.Mask" user "Board Geometry/Soldermask Bottom")
		(17 "Dwgs.User" user "User.Drawings")
		(19 "Cmts.User" user "User.Comments")
		(21 "Eco1.User" user "User.Eco1")
		(23 "Eco2.User" user "User.Eco2")
		(25 "Edge.Cuts" user "Board Geometry/Outline")
		(27 "Margin" user)
		(31 "F.CrtYd" user "Package Geometry/Place Bound Top")
		(29 "B.CrtYd" user "Package Geometry/Place Bound Bottom")
		(35 "F.Fab" user "Ref Des/Assembly Top")
		(33 "B.Fab" user "Ref Des/Assembly Bottom")
	)
	(footprint ""
		(layer "F.Cu")
		(at 410.226256 -57.26684 90)
		(property "Reference" "R8D23"
			(at 0 0 90)
			(layer "F.SilkS")
			(hide yes)
			(effects
				(font
					(size 1.27 1.27)
				)
			)
		)
		(property "Value" ""
			(at 0 0 90)
			(layer "F.Fab")
			(effects
				(font
					(size 1.27 1.27)
				)
			)
		)
		(duplicate_pad_numbers_are_jumpers no)
		(fp_poly
			(pts
				(xy -0.2794 -0.1016) (xy 0.2794 -0.1016) (xy 0.2794 0.9906) (xy -0.2794 0.9906)
			)
			(stroke
				(width 0)
				(type default)
			)
			(fill no)
			(layer "F.CrtYd")
		)
		(fp_line
			(start 0.2794 -0.1016)
			(end -0.2794 -0.1016)
			(stroke
				(width 0.1)
				(type default)
			)
			(layer "F.Fab")
		)
		(fp_line
			(start -0.2794 -0.1016)
			(end -0.2794 0.9906)
			(stroke
				(width 0.1)
				(type default)
			)
			(layer "F.Fab")
		)
		(fp_line
			(start 0.2794 0.9906)
			(end 0.2794 -0.1016)
			(stroke
				(width 0.1)
				(type default)
			)
			(layer "F.Fab")
		)
		(fp_line
			(start -0.2794 0.9906)
			(end 0.2794 0.9906)
			(stroke
				(width 0.1)
				(type default)
			)
			(layer "F.Fab")
		)
		(pad "1" smd rect
			(at 0 0 90)
			(size 0.508 0.508)
			(layers "F.Cu" "F.Mask" "F.Paste")
			(net "SMB_SENSOR_STBY_LVC3_SDA_R2")
		)
		(pad "2" smd rect
			(at 0 0.889 90)
			(size 0.508 0.508)
			(layers "F.Cu" "F.Mask" "F.Paste")
			(net "SMB_SENSOR_STBY_LVC3_SDA")
		)
		(zone
			(layer "F.Cu")
			(hatch none 0.5)
			(connect_pads
				(clearance 0)
			)
			(min_thickness 0.25)
			(keepout
				(tracks allowed)
				(vias not_allowed)
				(pads allowed)
				(copperpour not_allowed)
				(footprints allowed)
			)
			(placement
				(enabled no)
				(sheetname "")
			)
			(fill
				(thermal_gap 0.5)
				(thermal_bridge_width 0.5)
				(island_removal_mode 0)
			)
			(polygon
				(pts
					(xy 410.480256 -57.01284) (xy 410.480256 -57.52084) (xy 410.861256 -57.52084) (xy 410.861256 -57.01284)
				)
			)
		)
		(zone
			(layer "F.Cu")
			(hatch none 0.5)
			(connect_pads
				(clearance 0)
			)
			(min_thickness 0.25)
			(keepout
				(tracks not_allowed)
				(vias allowed)
				(pads allowed)
				(copperpour not_allowed)
				(footprints allowed)
			)
			(placement
				(enabled no)
				(sheetname "")
			)
			(fill
				(thermal_gap 0.5)
				(thermal_bridge_width 0.5)
				(island_removal_mode 0)
			)
			(polygon
				(pts
					(xy 410.861256 -57.01284) (xy 410.861256 -57.52084) (xy 410.480256 -57.52084) (xy 410.480256 -57.01284)
				)
			)
		)
	)
	(footprint ""
		(layer "F.Cu")
		(at 407.9875 -104.648 90)
		(property "Reference" "R2N7"
			(at 0 0 90)
			(layer "F.SilkS")
			(hide yes)
			(effects
				(font
					(size 1.27 1.27)
				)
			)
		)
		(property "Value" ""
			(at 0 0 90)
			(layer "F.Fab")
			(effects
				(font
					(size 1.27 1.27)
				)
			)
		)
		(duplicate_pad_numbers_are_jumpers no)
		(fp_poly
			(pts
				(xy -0.2794 -0.1016) (xy 0.2794 -0.1016) (xy 0.2794 0.9906) (xy -0.2794 0.9906)
			)
			(stroke
				(width 0)
				(type default)
			)
			(fill no)
			(layer "F.CrtYd")
		)
		(fp_line
			(start 0.2794 -0.1016)
			(end -0.2794 -0.1016)
			(stroke
				(width 0.1)
				(type default)
			)
			(layer "F.Fab")
		)
		(fp_line
			(start -0.2794 -0.1016)
			(end -0.2794 0.9906)
			(stroke
				(width 0.1)
				(type default)
			)
			(layer "F.Fab")
		)
		(fp_line
			(start 0.2794 0.9906)
			(end 0.2794 -0.1016)
			(stroke
				(width 0.1)
				(type default)
			)
			(layer "F.Fab")
		)
		(fp_line
			(start -0.2794 0.9906)
			(end 0.2794 0.9906)
			(stroke
				(width 0.1)
				(type default)
			)
			(layer "F.Fab")
		)
		(pad "1" smd rect
			(at 0 0 90)
			(size 0.508 0.508)
			(layers "F.Cu" "F.Mask" "F.Paste")
			(net "P3V3_STBY")
		)
		(pad "2" smd rect
			(at 0 0.889 90)
			(size 0.508 0.508)
			(layers "F.Cu" "F.Mask" "F.Paste")
			(net "IRQ_BOARD_BMC_ALERT_N")
		)
		(zone
			(layer "F.Cu")
			(hatch none 0.5)
			(connect_pads
				(clearance 0)
			)
			(min_thickness 0.25)
			(keepout
				(tracks allowed)
				(vias not_allowed)
				(pads allowed)
				(copperpour not_allowed)
				(footprints allowed)
			)
			(placement
				(enabled no)
				(sheetname "")
			)
			(fill
				(thermal_gap 0.5)
				(thermal_bridge_width 0.5)
				(island_removal_mode 0)
			)
			(polygon
				(pts
					(xy 408.2415 -104.394) (xy 408.2415 -104.902) (xy 408.6225 -104.902) (xy 408.6225 -104.394)
				)
			)
		)
		(zone
			(layer "F.Cu")
			(hatch none 0.5)
			(connect_pads
				(clearance 0)
			)
			(min_thickness 0.25)
			(keepout
				(tracks not_allowed)
				(vias allowed)
				(pads allowed)
				(copperpour not_allowed)
				(footprints allowed)
			)
			(placement
				(enabled no)
				(sheetname "")
			)
			(fill
				(thermal_gap 0.5)
				(thermal_bridge_width 0.5)
				(island_removal_mode 0)
			)
			(polygon
				(pts
					(xy 408.6225 -104.394) (xy 408.6225 -104.902) (xy 408.2415 -104.902) (xy 408.2415 -104.394)
				)
			)
		)
	)
	(footprint ""
		(layer "F.Cu")
		(at 28.83408 -99.60102 90)
		(property "Reference" "C1C12"
			(at 0 0 90)
			(layer "F.SilkS")
			(hide yes)
			(effects
				(font
					(size 1.27 1.27)
				)
			)
		)
		(property "Value" ""
			(at 0 0 90)
			(layer "F.Fab")
			(effects
				(font
					(size 1.27 1.27)
				)
			)
		)
		(duplicate_pad_numbers_are_jumpers no)
		(fp_rect
			(start -0.3048 0.9906)
			(end 0.3048 -0.1016)
			(stroke
				(width 0)
				(type default)
			)
			(fill no)
			(layer "F.CrtYd")
		)
		(fp_line
			(start 0.3048 -0.1016)
			(end -0.3048 -0.1016)
			(stroke
				(width 0.1)
				(type default)
			)
			(layer "F.Fab")
		)
		(fp_line
			(start -0.3048 -0.1016)
			(end -0.3048 0.9906)
			(stroke
				(width 0.1)
				(type default)
			)
			(layer "F.Fab")
		)
		(fp_line
			(start 0.3048 0.9906)
			(end 0.3048 -0.1016)
			(stroke
				(width 0.1)
				(type default)
			)
			(layer "F.Fab")
		)
		(fp_line
			(start -0.3048 0.9906)
			(end 0.3048 0.9906)
			(stroke
				(width 0.1)
				(type default)
			)
			(layer "F.Fab")
		)
		(pad "1" smd rect
			(at 0 0 90)
			(size 0.508 0.508)
			(layers "F.Cu" "F.Mask" "F.Paste")
			(net "VR_PVSA_CPU1_BOOT")
		)
		(pad "2" smd rect
			(at 0 0.889 90)
			(size 0.508 0.508)
			(layers "F.Cu" "F.Mask" "F.Paste")
			(net "VR_PVSA_CPU1_PHASE")
		)
		(zone
			(layer "F.Cu")
			(hatch none 0.5)
			(connect_pads
				(clearance 0)
			)
			(min_thickness 0.25)
			(keepout
				(tracks not_allowed)
				(vias allowed)
				(pads allowed)
				(copperpour not_allowed)
				(footprints allowed)
			)
			(placement
				(enabled no)
				(sheetname "")
			)
			(fill
				(thermal_gap 0.5)
				(thermal_bridge_width 0.5)
				(island_removal_mode 0)
			)
			(polygon
				(pts
					(xy 29.46908 -99.34702) (xy 29.46908 -99.85502) (xy 29.08808 -99.85502) (xy 29.08808 -99.34702)
				)
			)
		)
		(zone
			(layer "F.Cu")
			(hatch none 0.5)
			(connect_pads
				(clearance 0)
			)
			(min_thickness 0.25)
			(keepout
				(tracks allowed)
				(vias not_allowed)
				(pads allowed)
				(copperpour not_allowed)
				(footprints allowed)
			)
			(placement
				(enabled no)
				(sheetname "")
			)
			(fill
				(thermal_gap 0.5)
				(thermal_bridge_width 0.5)
				(island_removal_mode 0)
			)
			(polygon
				(pts
					(xy 29.46908 -99.34702) (xy 29.46908 -99.85502) (xy 29.08808 -99.85502) (xy 29.08808 -99.34702)
				)
			)
		)
	)
	(footprint ""
		(layer "F.Cu")
		(at 404.495 -22.098 180)
		(property "Reference" "R25W112"
			(at -0.8382 -0.67818 180)
			(unlocked yes)
			(layer "F.SilkS")
			(effects
				(font
					(size 0.4064 0.254)
					(thickness 0.1524)
				)
				(justify left)
			)
		)
		(property "Value" ""
			(at 0 0 180)
			(layer "F.Fab")
			(effects
				(font
					(size 1.27 1.27)
				)
			)
		)
		(duplicate_pad_numbers_are_jumpers no)
		(fp_poly
			(pts
				(xy -0.2794 -0.1016) (xy 0.2794 -0.1016) (xy 0.2794 0.9906) (xy -0.2794 0.9906)
			)
			(stroke
				(width 0)
				(type default)
			)
			(fill no)
			(layer "F.CrtYd")
		)
		(fp_line
			(start 0.2794 0.9906)
			(end 0.2794 -0.1016)
			(stroke
				(width 0.1)
				(type default)
			)
			(layer "F.Fab")
		)
		(fp_line
			(start 0.2794 -0.1016)
			(end -0.2794 -0.1016)
			(stroke
				(width 0.1)
				(type default)
			)
			(layer "F.Fab")
		)
		(fp_line
			(start -0.2794 0.9906)
			(end 0.2794 0.9906)
			(stroke
				(width 0.1)
				(type default)
			)
			(layer "F.Fab")
		)
		(fp_line
			(start -0.2794 -0.1016)
			(end -0.2794 0.9906)
			(stroke
				(width 0.1)
				(type default)
			)
			(layer "F.Fab")
		)
		(pad "1" smd rect
			(at 0 0 180)
			(size 0.508 0.508)
			(layers "F.Cu" "F.Mask" "F.Paste")
			(net "P3V3_STBY")
		)
		(pad "2" smd rect
			(at 0 0.889 180)
			(size 0.508 0.508)
			(layers "F.Cu" "F.Mask" "F.Paste")
			(net "RMII_BMC_PCH_SPRNGVLLE_TXD0_R")
		)
		(zone
			(layer "F.Cu")
			(hatch none 0.5)
			(connect_pads
				(clearance 0)
			)
			(min_thickness 0.25)
			(keepout
				(tracks not_allowed)
				(vias allowed)
				(pads allowed)
				(copperpour not_allowed)
				(footprints allowed)
			)
			(placement
				(enabled no)
				(sheetname "")
			)
			(fill
				(thermal_gap 0.5)
				(thermal_bridge_width 0.5)
				(island_removal_mode 0)
			)
			(polygon
				(pts
					(xy 404.749 -22.733) (xy 404.241 -22.733) (xy 404.241 -22.352) (xy 404.749 -22.352)
				)
			)
		)
		(zone
			(layer "F.Cu")
			(hatch none 0.5)
			(connect_pads
				(clearance 0)
			)
			(min_thickness 0.25)
			(keepout
				(tracks allowed)
				(vias not_allowed)
				(pads allowed)
				(copperpour not_allowed)
				(footprints allowed)
			)
			(placement
				(enabled no)
				(sheetname "")
			)
			(fill
				(thermal_gap 0.5)
				(thermal_bridge_width 0.5)
				(island_removal_mode 0)
			)
			(polygon
				(pts
					(xy 404.749 -22.352) (xy 404.241 -22.352) (xy 404.241 -22.733) (xy 404.749 -22.733)
				)
			)
		)
	)
	(footprint ""
		(layer "F.Cu")
		(at 370.7384 -127.762 -90)
		(property "Reference" "R7B8"
			(at 0 0 270)
			(layer "F.SilkS")
			(hide yes)
			(effects
				(font
					(size 1.27 1.27)
				)
			)
		)
		(property "Value" ""
			(at 0 0 270)
			(layer "F.Fab")
			(effects
				(font
					(size 1.27 1.27)
				)
			)
		)
		(duplicate_pad_numbers_are_jumpers no)
		(fp_poly
			(pts
				(xy -0.2794 -0.1016) (xy 0.2794 -0.1016) (xy 0.2794 0.9906) (xy -0.2794 0.9906)
			)
			(stroke
				(width 0)
				(type default)
			)
			(fill no)
			(layer "F.CrtYd")
		)
		(fp_line
			(start -0.2794 0.9906)
			(end 0.2794 0.9906)
			(stroke
				(width 0.1)
				(type default)
			)
			(layer "F.Fab")
		)
		(fp_line
			(start 0.2794 0.9906)
			(end 0.2794 -0.1016)
			(stroke
				(width 0.1)
				(type default)
			)
			(layer "F.Fab")
		)
		(fp_line
			(start -0.2794 -0.1016)
			(end -0.2794 0.9906)
			(stroke
				(width 0.1)
				(type default)
			)
			(layer "F.Fab")
		)
		(fp_line
			(start 0.2794 -0.1016)
			(end -0.2794 -0.1016)
			(stroke
				(width 0.1)
				(type default)
			)
			(layer "F.Fab")
		)
		(pad "1" smd rect
			(at 0 0 270)
			(size 0.508 0.508)
			(layers "F.Cu" "F.Mask" "F.Paste")
			(net "A_EXTCLKN")
		)
		(pad "2" smd rect
			(at 0 0.889 270)
			(size 0.508 0.508)
			(layers "F.Cu" "F.Mask" "F.Paste")
			(net "GND")
		)
		(zone
			(layer "F.Cu")
			(hatch none 0.5)
			(connect_pads
				(clearance 0)
			)
			(min_thickness 0.25)
			(keepout
				(tracks not_allowed)
				(vias allowed)
				(pads allowed)
				(copperpour not_allowed)
				(footprints allowed)
			)
			(placement
				(enabled no)
				(sheetname "")
			)
			(fill
				(thermal_gap 0.5)
				(thermal_bridge_width 0.5)
				(island_removal_mode 0)
			)
			(polygon
				(pts
					(xy 370.1034 -128.016) (xy 370.1034 -127.508) (xy 370.4844 -127.508) (xy 370.4844 -128.016)
				)
			)
		)
		(zone
			(layer "F.Cu")
			(hatch none 0.5)
			(connect_pads
				(clearance 0)
			)
			(min_thickness 0.25)
			(keepout
				(tracks allowed)
				(vias not_allowed)
				(pads allowed)
				(copperpour not_allowed)
				(footprints allowed)
			)
			(placement
				(enabled no)
				(sheetname "")
			)
			(fill
				(thermal_gap 0.5)
				(thermal_bridge_width 0.5)
				(island_removal_mode 0)
			)
			(polygon
				(pts
					(xy 370.4844 -128.016) (xy 370.4844 -127.508) (xy 370.1034 -127.508) (xy 370.1034 -128.016)
				)
			)
		)
	)
	(footprint ""
		(layer "F.Cu")
		(at 402.615146 -42.935652 90)
		(property "Reference" "R1T36"
			(at 0 0 90)
			(layer "F.SilkS")
			(hide yes)
			(effects
				(font
					(size 1.27 1.27)
				)
			)
		)
		(property "Value" ""
			(at 0 0 90)
			(layer "F.Fab")
			(effects
				(font
					(size 1.27 1.27)
				)
			)
		)
		(duplicate_pad_numbers_are_jumpers no)
		(fp_poly
			(pts
				(xy -0.2794 -0.1016) (xy 0.2794 -0.1016) (xy 0.2794 0.9906) (xy -0.2794 0.9906)
			)
			(stroke
				(width 0)
				(type default)
			)
			(fill no)
			(layer "F.CrtYd")
		)
		(fp_line
			(start 0.2794 -0.1016)
			(end -0.2794 -0.1016)
			(stroke
				(width 0.1)
				(type default)
			)
			(layer "F.Fab")
		)
		(fp_line
			(start -0.2794 -0.1016)
			(end -0.2794 0.9906)
			(stroke
				(width 0.1)
				(type default)
			)
			(layer "F.Fab")
		)
		(fp_line
			(start 0.2794 0.9906)
			(end 0.2794 -0.1016)
			(stroke
				(width 0.1)
				(type default)
			)
			(layer "F.Fab")
		)
		(fp_line
			(start -0.2794 0.9906)
			(end 0.2794 0.9906)
			(stroke
				(width 0.1)
				(type default)
			)
			(layer "F.Fab")
		)
		(pad "1" smd rect
			(at 0 0 90)
			(size 0.508 0.508)
			(layers "F.Cu" "F.Mask" "F.Paste")
			(net "FM_CPU0_PROCHOT_LVT3_N")
		)
		(pad "2" smd rect
			(at 0 0.889 90)
			(size 0.508 0.508)
			(layers "F.Cu" "F.Mask" "F.Paste")
			(net "FM_CPU0_PROCHOT_LVT3_BMC_N")
		)
		(zone
			(layer "F.Cu")
			(hatch none 0.5)
			(connect_pads
				(clearance 0)
			)
			(min_thickness 0.25)
			(keepout
				(tracks allowed)
				(vias not_allowed)
				(pads allowed)
				(copperpour not_allowed)
				(footprints allowed)
			)
			(placement
				(enabled no)
				(sheetname "")
			)
			(fill
				(thermal_gap 0.5)
				(thermal_bridge_width 0.5)
				(island_removal_mode 0)
			)
			(polygon
				(pts
					(xy 402.869146 -42.681652) (xy 402.869146 -43.189652) (xy 403.250146 -43.189652) (xy 403.250146 -42.681652)
				)
			)
		)
		(zone
			(layer "F.Cu")
			(hatch none 0.5)
			(connect_pads
				(clearance 0)
			)
			(min_thickness 0.25)
			(keepout
				(tracks not_allowed)
				(vias allowed)
				(pads allowed)
				(copperpour not_allowed)
				(footprints allowed)
			)
			(placement
				(enabled no)
				(sheetname "")
			)
			(fill
				(thermal_gap 0.5)
				(thermal_bridge_width 0.5)
				(island_removal_mode 0)
			)
			(polygon
				(pts
					(xy 403.250146 -42.681652) (xy 403.250146 -43.189652) (xy 402.869146 -43.189652) (xy 402.869146 -42.681652)
				)
			)
		)
	)
	(footprint ""
		(layer "F.Cu")
		(at 398.8689 -87.4649 -90)
		(property "Reference" "R2P17"
			(at 0 0 270)
			(layer "F.SilkS")
			(hide yes)
			(effects
				(font
					(size 1.27 1.27)
				)
			)
		)
		(property "Value" ""
			(at 0 0 270)
			(layer "F.Fab")
			(effects
				(font
					(size 1.27 1.27)
				)
			)
		)
		(duplicate_pad_numbers_are_jumpers no)
		(fp_poly
			(pts
				(xy -0.2794 -0.1016) (xy 0.2794 -0.1016) (xy 0.2794 0.9906) (xy -0.2794 0.9906)
			)
			(stroke
				(width 0)
				(type default)
			)
			(fill no)
			(layer "F.CrtYd")
		)
		(fp_line
			(start -0.2794 0.9906)
			(end 0.2794 0.9906)
			(stroke
				(width 0.1)
				(type default)
			)
			(layer "F.Fab")
		)
		(fp_line
			(start 0.2794 0.9906)
			(end 0.2794 -0.1016)
			(stroke
				(width 0.1)
				(type default)
			)
			(layer "F.Fab")
		)
		(fp_line
			(start -0.2794 -0.1016)
			(end -0.2794 0.9906)
			(stroke
				(width 0.1)
				(type default)
			)
			(layer "F.Fab")
		)
		(fp_line
			(start 0.2794 -0.1016)
			(end -0.2794 -0.1016)
			(stroke
				(width 0.1)
				(type default)
			)
			(layer "F.Fab")
		)
		(pad "1" smd rect
			(at 0 0 270)
			(size 0.508 0.508)
			(layers "F.Cu" "F.Mask" "F.Paste")
			(net "P3V3_STBY")
		)
		(pad "2" smd rect
			(at 0 0.889 270)
			(size 0.508 0.508)
			(layers "F.Cu" "F.Mask" "F.Paste")
			(net "FM_PCH_BMC_THERMTRIP_N")
		)
		(zone
			(layer "F.Cu")
			(hatch none 0.5)
			(connect_pads
				(clearance 0)
			)
			(min_thickness 0.25)
			(keepout
				(tracks not_allowed)
				(vias allowed)
				(pads allowed)
				(copperpour not_allowed)
				(footprints allowed)
			)
			(placement
				(enabled no)
				(sheetname "")
			)
			(fill
				(thermal_gap 0.5)
				(thermal_bridge_width 0.5)
				(island_removal_mode 0)
			)
			(polygon
				(pts
					(xy 398.2339 -87.7189) (xy 398.2339 -87.2109) (xy 398.6149 -87.2109) (xy 398.6149 -87.7189)
				)
			)
		)
		(zone
			(layer "F.Cu")
			(hatch none 0.5)
			(connect_pads
				(clearance 0)
			)
			(min_thickness 0.25)
			(keepout
				(tracks allowed)
				(vias not_allowed)
				(pads allowed)
				(copperpour not_allowed)
				(footprints allowed)
			)
			(placement
				(enabled no)
				(sheetname "")
			)
			(fill
				(thermal_gap 0.5)
				(thermal_bridge_width 0.5)
				(island_removal_mode 0)
			)
			(polygon
				(pts
					(xy 398.6149 -87.7189) (xy 398.6149 -87.2109) (xy 398.2339 -87.2109) (xy 398.2339 -87.7189)
				)
			)
		)
	)
)
